(kicad_pcb
	(version 20260206)
	(generator "pcbnew")
	(generator_version "10.0")
	(general
		(thickness 1.6)
		(legacy_teardrops no)
	)
	(paper "A4")
	(title_block
		(title "04192023_DAF0TMB3IC0_F0TG_MB_C_brd_V02_OCP.brd")
		(comment 1 "Grand Teton / footprints 436-443 of 8354")
	)
	(layers
		(0 "F.Cu" signal "TOP")
		(4 "In1.Cu" signal "GND")
		(6 "In2.Cu" signal "IN1")
		(8 "In3.Cu" signal "GND1")
		(10 "In4.Cu" signal "IN2")
		(12 "In5.Cu" signal "GND2")
		(14 "In6.Cu" signal "IN3")
		(16 "In7.Cu" signal "GND3")
		(18 "In8.Cu" signal "VCC")
		(20 "In9.Cu" signal "VCC1")
		(22 "In10.Cu" signal "GND4")
		(24 "In11.Cu" signal "IN4")
		(26 "In12.Cu" signal "GND5")
		(28 "In13.Cu" signal "IN5")
		(30 "In14.Cu" signal "GND6")
		(32 "In15.Cu" signal "IN6")
		(34 "In16.Cu" signal "GND7")
		(2 "B.Cu" signal "BOTTOM")
		(9 "F.Adhes" user "F.Adhesive")
		(11 "B.Adhes" user "B.Adhesive")
		(13 "F.Paste" user "Package Geometry/Pastemask Top")
		(15 "B.Paste" user "Package Geometry/Pastemask Bottom")
		(5 "F.SilkS" user "Ref Des/Silkscreen Top")
		(7 "B.SilkS" user "Ref Des/Silkscreen Bottom")
		(1 "F.Mask" user "Board Geometry/Soldermask Top")
		(3 "B.Mask" user "Board Geometry/Soldermask Bottom")
		(17 "Dwgs.User" user "User.Drawings")
		(19 "Cmts.User" user "User.Comments")
		(21 "Eco1.User" user "User.Eco1")
		(23 "Eco2.User" user "User.Eco2")
		(25 "Edge.Cuts" user "Board Geometry/Outline")
		(27 "Margin" user)
		(31 "F.CrtYd" user "Package Geometry/Place Bound Top")
		(29 "B.CrtYd" user "Package Geometry/Place Bound Bottom")
		(35 "F.Fab" user "Ref Des/Assembly Top")
		(33 "B.Fab" user "Ref Des/Assembly Bottom")
	)
	(footprint ""
		(layer "F.Cu")
		(at 426.213778 -400.456146)
		(property "Reference" "C795"
			(at 0 0 0)
			(layer "F.SilkS")
			(hide yes)
			(effects
				(font
					(size 1.27 1.27)
				)
			)
		)
		(property "Value" ""
			(at 0 0 0)
			(layer "F.Fab")
			(effects
				(font
					(size 1.27 1.27)
				)
			)
		)
		(duplicate_pad_numbers_are_jumpers no)
		(fp_line
			(start -1.524 -0.762)
			(end 1.524 -0.762)
			(stroke
				(width 0.1524)
				(type default)
			)
			(layer "F.SilkS")
		)
		(fp_line
			(start -1.524 0.762)
			(end -1.524 -0.762)
			(stroke
				(width 0.1524)
				(type default)
			)
			(layer "F.SilkS")
		)
		(fp_line
			(start 1.524 -0.762)
			(end 1.524 0.762)
			(stroke
				(width 0.1524)
				(type default)
			)
			(layer "F.SilkS")
		)
		(fp_line
			(start 1.524 0.762)
			(end -1.524 0.762)
			(stroke
				(width 0.1524)
				(type default)
			)
			(layer "F.SilkS")
		)
		(fp_line
			(start -1.1049 -0.724916)
			(end -1.1049 0.724916)
			(stroke
				(width 0.1)
				(type default)
			)
			(layer "F.Fab")
		)
		(fp_line
			(start -1.1049 0.724916)
			(end 1.1049 0.724916)
			(stroke
				(width 0.1)
				(type default)
			)
			(layer "F.Fab")
		)
		(fp_line
			(start 1.1049 -0.724916)
			(end -1.1049 -0.724916)
			(stroke
				(width 0.1)
				(type default)
			)
			(layer "F.Fab")
		)
		(fp_line
			(start 1.1049 0.724916)
			(end 1.1049 -0.724916)
			(stroke
				(width 0.1)
				(type default)
			)
			(layer "F.Fab")
		)
		(pad "1" smd rect
			(at -0.889 0 180)
			(size 1.016 1.27)
			(layers "F.Cu" "F.Mask" "F.Paste")
			(net "P0V9_CPU0_RT2_2A")
		)
		(pad "2" smd rect
			(at 0.889 0 180)
			(size 1.016 1.27)
			(layers "F.Cu" "F.Mask" "F.Paste")
			(net "GND")
		)
	)
	(footprint ""
		(layer "F.Cu")
		(at 340.696296 -339.881972 90)
		(property "Reference" "PC132_5"
			(at 0 0 90)
			(layer "F.SilkS")
			(hide yes)
			(effects
				(font
					(size 1.27 1.27)
				)
			)
		)
		(property "Value" ""
			(at 0 0 90)
			(layer "F.Fab")
			(effects
				(font
					(size 1.27 1.27)
				)
			)
		)
		(duplicate_pad_numbers_are_jumpers no)
		(fp_line
			(start 0.7874 -0.4064)
			(end 0.7874 0.4064)
			(stroke
				(width 0.1524)
				(type default)
			)
			(layer "F.SilkS")
		)
		(fp_line
			(start -0.7874 -0.4064)
			(end 0.7874 -0.4064)
			(stroke
				(width 0.1524)
				(type default)
			)
			(layer "F.SilkS")
		)
		(fp_line
			(start 0.7874 0.4064)
			(end -0.7874 0.4064)
			(stroke
				(width 0.1524)
				(type default)
			)
			(layer "F.SilkS")
		)
		(fp_line
			(start -0.7874 0.4064)
			(end -0.7874 -0.4064)
			(stroke
				(width 0.1524)
				(type default)
			)
			(layer "F.SilkS")
		)
		(fp_line
			(start -0.12065 -0.305054)
			(end -0.12065 -0.2794)
			(stroke
				(width 0.1)
				(type default)
			)
			(layer "F.Fab")
		)
		(fp_line
			(start -0.67945 -0.305054)
			(end -0.12065 -0.305054)
			(stroke
				(width 0.1)
				(type default)
			)
			(layer "F.Fab")
		)
		(fp_line
			(start 0.67945 -0.3048)
			(end 0.67945 0.3048)
			(stroke
				(width 0.1)
				(type default)
			)
			(layer "F.Fab")
		)
		(fp_line
			(start 0.12065 -0.3048)
			(end 0.67945 -0.3048)
			(stroke
				(width 0.1)
				(type default)
			)
			(layer "F.Fab")
		)
		(fp_line
			(start 0.12065 -0.2794)
			(end 0.12065 -0.3048)
			(stroke
				(width 0.1)
				(type default)
			)
			(layer "F.Fab")
		)
		(fp_line
			(start -0.12065 -0.2794)
			(end 0.12065 -0.2794)
			(stroke
				(width 0.1)
				(type default)
			)
			(layer "F.Fab")
		)
		(fp_line
			(start 0.120396 0.2794)
			(end -0.12065 0.2794)
			(stroke
				(width 0.1)
				(type default)
			)
			(layer "F.Fab")
		)
		(fp_line
			(start -0.12065 0.2794)
			(end -0.12065 0.3048)
			(stroke
				(width 0.1)
				(type default)
			)
			(layer "F.Fab")
		)
		(fp_line
			(start 0.67945 0.3048)
			(end 0.120396 0.3048)
			(stroke
				(width 0.1)
				(type default)
			)
			(layer "F.Fab")
		)
		(fp_line
			(start 0.120396 0.3048)
			(end 0.120396 0.2794)
			(stroke
				(width 0.1)
				(type default)
			)
			(layer "F.Fab")
		)
		(fp_line
			(start -0.12065 0.3048)
			(end -0.67945 0.3048)
			(stroke
				(width 0.1)
				(type default)
			)
			(layer "F.Fab")
		)
		(fp_line
			(start -0.67945 0.3048)
			(end -0.67945 -0.305054)
			(stroke
				(width 0.1)
				(type default)
			)
			(layer "F.Fab")
		)
		(pad "1" smd circle
			(at -0.40005 0 90)
			(size 0 0)
			(layers "F.Cu" "F.Mask" "F.Paste")
			(net "PVDDCR_CPU1_P0_VCCS")
		)
		(pad "2" smd circle
			(at 0.40005 0 90)
			(size 0 0)
			(layers "F.Cu" "F.Mask" "F.Paste")
			(net "GND")
		)
	)
	(footprint ""
		(layer "F.Cu")
		(at 179.236878 -351.293684 -90)
		(property "Reference" "PC507_11P1_1"
			(at 0 0 270)
			(layer "F.SilkS")
			(hide yes)
			(effects
				(font
					(size 1.27 1.27)
				)
			)
		)
		(property "Value" ""
			(at 0 0 270)
			(layer "F.Fab")
			(effects
				(font
					(size 1.27 1.27)
				)
			)
		)
		(duplicate_pad_numbers_are_jumpers no)
		(fp_line
			(start -0.7874 0.4064)
			(end -0.7874 -0.4064)
			(stroke
				(width 0.1524)
				(type default)
			)
			(layer "F.SilkS")
		)
		(fp_line
			(start 0.7874 0.4064)
			(end -0.7874 0.4064)
			(stroke
				(width 0.1524)
				(type default)
			)
			(layer "F.SilkS")
		)
		(fp_line
			(start -0.7874 -0.4064)
			(end 0.7874 -0.4064)
			(stroke
				(width 0.1524)
				(type default)
			)
			(layer "F.SilkS")
		)
		(fp_line
			(start 0.7874 -0.4064)
			(end 0.7874 0.4064)
			(stroke
				(width 0.1524)
				(type default)
			)
			(layer "F.SilkS")
		)
		(fp_line
			(start -0.67945 0.3048)
			(end -0.67945 -0.305054)
			(stroke
				(width 0.1)
				(type default)
			)
			(layer "F.Fab")
		)
		(fp_line
			(start -0.12065 0.3048)
			(end -0.67945 0.3048)
			(stroke
				(width 0.1)
				(type default)
			)
			(layer "F.Fab")
		)
		(fp_line
			(start 0.120396 0.3048)
			(end 0.120396 0.2794)
			(stroke
				(width 0.1)
				(type default)
			)
			(layer "F.Fab")
		)
		(fp_line
			(start 0.67945 0.3048)
			(end 0.120396 0.3048)
			(stroke
				(width 0.1)
				(type default)
			)
			(layer "F.Fab")
		)
		(fp_line
			(start -0.12065 0.2794)
			(end -0.12065 0.3048)
			(stroke
				(width 0.1)
				(type default)
			)
			(layer "F.Fab")
		)
		(fp_line
			(start 0.120396 0.2794)
			(end -0.12065 0.2794)
			(stroke
				(width 0.1)
				(type default)
			)
			(layer "F.Fab")
		)
		(fp_line
			(start -0.12065 -0.2794)
			(end 0.12065 -0.2794)
			(stroke
				(width 0.1)
				(type default)
			)
			(layer "F.Fab")
		)
		(fp_line
			(start 0.12065 -0.2794)
			(end 0.12065 -0.3048)
			(stroke
				(width 0.1)
				(type default)
			)
			(layer "F.Fab")
		)
		(fp_line
			(start 0.12065 -0.3048)
			(end 0.67945 -0.3048)
			(stroke
				(width 0.1)
				(type default)
			)
			(layer "F.Fab")
		)
		(fp_line
			(start 0.67945 -0.3048)
			(end 0.67945 0.3048)
			(stroke
				(width 0.1)
				(type default)
			)
			(layer "F.Fab")
		)
		(fp_line
			(start -0.67945 -0.305054)
			(end -0.12065 -0.305054)
			(stroke
				(width 0.1)
				(type default)
			)
			(layer "F.Fab")
		)
		(fp_line
			(start -0.12065 -0.305054)
			(end -0.12065 -0.2794)
			(stroke
				(width 0.1)
				(type default)
			)
			(layer "F.Fab")
		)
		(pad "1" smd circle
			(at -0.40005 0 270)
			(size 0 0)
			(layers "F.Cu" "F.Mask" "F.Paste")
			(net "PVDD11_S3_P1_PVCC")
		)
		(pad "2" smd circle
			(at 0.40005 0 270)
			(size 0 0)
			(layers "F.Cu" "F.Mask" "F.Paste")
			(net "GND")
		)
	)
	(footprint ""
		(layer "F.Cu")
		(at 315.220096 -378.95403 -90)
		(property "Reference" "C914"
			(at 0 0 270)
			(layer "F.SilkS")
			(hide yes)
			(effects
				(font
					(size 1.27 1.27)
				)
			)
		)
		(property "Value" ""
			(at 0 0 270)
			(layer "F.Fab")
			(effects
				(font
					(size 1.27 1.27)
				)
			)
		)
		(duplicate_pad_numbers_are_jumpers no)
		(fp_line
			(start -0.299974 0.150114)
			(end -0.299974 -0.150114)
			(stroke
				(width 0.1)
				(type default)
			)
			(layer "F.Fab")
		)
		(fp_line
			(start 0.299974 0.150114)
			(end -0.299974 0.150114)
			(stroke
				(width 0.1)
				(type default)
			)
			(layer "F.Fab")
		)
		(fp_line
			(start -0.299974 -0.150114)
			(end 0.299974 -0.150114)
			(stroke
				(width 0.1)
				(type default)
			)
			(layer "F.Fab")
		)
		(fp_line
			(start 0.299974 -0.150114)
			(end 0.299974 0.150114)
			(stroke
				(width 0.1)
				(type default)
			)
			(layer "F.Fab")
		)
		(pad "1" smd rect
			(at -0.2667 0 270)
			(size 0.3048 0.381)
			(layers "F.Cu" "F.Mask" "F.Paste")
			(net "P5E_CPU0_P0_TX_C_DN<9>")
		)
		(pad "2" smd rect
			(at 0.2667 0 270)
			(size 0.3048 0.381)
			(layers "F.Cu" "F.Mask" "F.Paste")
			(net "P5E_CPU0_P0_TX_DN<9>")
		)
	)
	(footprint ""
		(layer "F.Cu")
		(at 415.628582 -331.945996)
		(property "Reference" "PR115"
			(at 0 0 0)
			(layer "F.SilkS")
			(hide yes)
			(effects
				(font
					(size 1.27 1.27)
				)
			)
		)
		(property "Value" ""
			(at 0 0 0)
			(layer "F.Fab")
			(effects
				(font
					(size 1.27 1.27)
				)
			)
		)
		(duplicate_pad_numbers_are_jumpers no)
		(fp_line
			(start -0.7874 -0.4064)
			(end 0.7874 -0.4064)
			(stroke
				(width 0.1524)
				(type default)
			)
			(layer "F.SilkS")
		)
		(fp_line
			(start -0.7874 0.4064)
			(end -0.7874 -0.4064)
			(stroke
				(width 0.1524)
				(type default)
			)
			(layer "F.SilkS")
		)
		(fp_line
			(start 0.7874 -0.4064)
			(end 0.7874 0.4064)
			(stroke
				(width 0.1524)
				(type default)
			)
			(layer "F.SilkS")
		)
		(fp_line
			(start 0.7874 0.4064)
			(end -0.7874 0.4064)
			(stroke
				(width 0.1524)
				(type default)
			)
			(layer "F.SilkS")
		)
		(fp_line
			(start -0.67945 -0.305054)
			(end -0.12065 -0.305054)
			(stroke
				(width 0.1)
				(type default)
			)
			(layer "F.Fab")
		)
		(fp_line
			(start -0.67945 0.3048)
			(end -0.67945 -0.305054)
			(stroke
				(width 0.1)
				(type default)
			)
			(layer "F.Fab")
		)
		(fp_line
			(start -0.12065 -0.305054)
			(end -0.12065 -0.2794)
			(stroke
				(width 0.1)
				(type default)
			)
			(layer "F.Fab")
		)
		(fp_line
			(start -0.12065 -0.2794)
			(end 0.12065 -0.2794)
			(stroke
				(width 0.1)
				(type default)
			)
			(layer "F.Fab")
		)
		(fp_line
			(start -0.12065 0.2794)
			(end -0.12065 0.3048)
			(stroke
				(width 0.1)
				(type default)
			)
			(layer "F.Fab")
		)
		(fp_line
			(start -0.12065 0.3048)
			(end -0.67945 0.3048)
			(stroke
				(width 0.1)
				(type default)
			)
			(layer "F.Fab")
		)
		(fp_line
			(start 0.120396 0.2794)
			(end -0.12065 0.2794)
			(stroke
				(width 0.1)
				(type default)
			)
			(layer "F.Fab")
		)
		(fp_line
			(start 0.120396 0.3048)
			(end 0.120396 0.2794)
			(stroke
				(width 0.1)
				(type default)
			)
			(layer "F.Fab")
		)
		(fp_line
			(start 0.12065 -0.3048)
			(end 0.67945 -0.3048)
			(stroke
				(width 0.1)
				(type default)
			)
			(layer "F.Fab")
		)
		(fp_line
			(start 0.12065 -0.2794)
			(end 0.12065 -0.3048)
			(stroke
				(width 0.1)
				(type default)
			)
			(layer "F.Fab")
		)
		(fp_line
			(start 0.67945 -0.3048)
			(end 0.67945 0.3048)
			(stroke
				(width 0.1)
				(type default)
			)
			(layer "F.Fab")
		)
		(fp_line
			(start 0.67945 0.3048)
			(end 0.120396 0.3048)
			(stroke
				(width 0.1)
				(type default)
			)
			(layer "F.Fab")
		)
		(pad "1" smd circle
			(at -0.40005 0)
			(size 0 0)
			(layers "F.Cu" "F.Mask" "F.Paste")
			(net "VSENSE_VSS_SENSE_C_P0")
		)
		(pad "2" smd circle
			(at 0.40005 0)
			(size 0 0)
			(layers "F.Cu" "F.Mask" "F.Paste")
			(net "GND")
		)
	)
	(footprint ""
		(layer "F.Cu")
		(at 163.703 -112.359948 180)
		(property "Reference" "R1071"
			(at 0 0 180)
			(layer "F.SilkS")
			(hide yes)
			(effects
				(font
					(size 1.27 1.27)
				)
			)
		)
		(property "Value" ""
			(at 0 0 180)
			(layer "F.Fab")
			(effects
				(font
					(size 1.27 1.27)
				)
			)
		)
		(duplicate_pad_numbers_are_jumpers no)
		(fp_line
			(start 0.7874 0.4064)
			(end -0.7874 0.4064)
			(stroke
				(width 0.1524)
				(type default)
			)
			(layer "F.SilkS")
		)
		(fp_line
			(start 0.7874 -0.4064)
			(end 0.7874 0.4064)
			(stroke
				(width 0.1524)
				(type default)
			)
			(layer "F.SilkS")
		)
		(fp_line
			(start -0.7874 0.4064)
			(end -0.7874 -0.4064)
			(stroke
				(width 0.1524)
				(type default)
			)
			(layer "F.SilkS")
		)
		(fp_line
			(start -0.7874 -0.4064)
			(end 0.7874 -0.4064)
			(stroke
				(width 0.1524)
				(type default)
			)
			(layer "F.SilkS")
		)
		(fp_line
			(start 0.67945 0.3048)
			(end 0.120396 0.3048)
			(stroke
				(width 0.1)
				(type default)
			)
			(layer "F.Fab")
		)
		(fp_line
			(start 0.67945 -0.3048)
			(end 0.67945 0.3048)
			(stroke
				(width 0.1)
				(type default)
			)
			(layer "F.Fab")
		)
		(fp_line
			(start 0.12065 -0.2794)
			(end 0.12065 -0.3048)
			(stroke
				(width 0.1)
				(type default)
			)
			(layer "F.Fab")
		)
		(fp_line
			(start 0.12065 -0.3048)
			(end 0.67945 -0.3048)
			(stroke
				(width 0.1)
				(type default)
			)
			(layer "F.Fab")
		)
		(fp_line
			(start 0.120396 0.3048)
			(end 0.120396 0.2794)
			(stroke
				(width 0.1)
				(type default)
			)
			(layer "F.Fab")
		)
		(fp_line
			(start 0.120396 0.2794)
			(end -0.12065 0.2794)
			(stroke
				(width 0.1)
				(type default)
			)
			(layer "F.Fab")
		)
		(fp_line
			(start -0.12065 0.3048)
			(end -0.67945 0.3048)
			(stroke
				(width 0.1)
				(type default)
			)
			(layer "F.Fab")
		)
		(fp_line
			(start -0.12065 0.2794)
			(end -0.12065 0.3048)
			(stroke
				(width 0.1)
				(type default)
			)
			(layer "F.Fab")
		)
		(fp_line
			(start -0.12065 -0.2794)
			(end 0.12065 -0.2794)
			(stroke
				(width 0.1)
				(type default)
			)
			(layer "F.Fab")
		)
		(fp_line
			(start -0.12065 -0.305054)
			(end -0.12065 -0.2794)
			(stroke
				(width 0.1)
				(type default)
			)
			(layer "F.Fab")
		)
		(fp_line
			(start -0.67945 0.3048)
			(end -0.67945 -0.305054)
			(stroke
				(width 0.1)
				(type default)
			)
			(layer "F.Fab")
		)
		(fp_line
			(start -0.67945 -0.305054)
			(end -0.12065 -0.305054)
			(stroke
				(width 0.1)
				(type default)
			)
			(layer "F.Fab")
		)
		(pad "1" smd circle
			(at -0.40005 0 180)
			(size 0 0)
			(layers "F.Cu" "F.Mask" "F.Paste")
			(net "P3V3_OCP_SFF_EN_R")
		)
		(pad "2" smd circle
			(at 0.40005 0 180)
			(size 0 0)
			(layers "F.Cu" "F.Mask" "F.Paste")
			(net "P3V3_AUX")
		)
	)
	(footprint ""
		(layer "F.Cu")
		(at 357.50881 -402.7424 -90)
		(property "Reference" "R1043"
			(at 0 0 270)
			(layer "F.SilkS")
			(hide yes)
			(effects
				(font
					(size 1.27 1.27)
				)
			)
		)
		(property "Value" ""
			(at 0 0 270)
			(layer "F.Fab")
			(effects
				(font
					(size 1.27 1.27)
				)
			)
		)
		(duplicate_pad_numbers_are_jumpers no)
		(fp_line
			(start -0.32512 0.175006)
			(end -0.32512 -0.175006)
			(stroke
				(width 0.1)
				(type default)
			)
			(layer "F.Fab")
		)
		(fp_line
			(start 0.32512 0.175006)
			(end -0.32512 0.175006)
			(stroke
				(width 0.1)
				(type default)
			)
			(layer "F.Fab")
		)
		(fp_line
			(start -0.32512 -0.175006)
			(end 0.32512 -0.175006)
			(stroke
				(width 0.1)
				(type default)
			)
			(layer "F.Fab")
		)
		(fp_line
			(start 0.32512 -0.175006)
			(end 0.32512 0.175006)
			(stroke
				(width 0.1)
				(type default)
			)
			(layer "F.Fab")
		)
		(pad "1" smd rect
			(at -0.2667 0 270)
			(size 0.3048 0.381)
			(layers "F.Cu" "F.Mask" "F.Paste")
			(net "NCF_A1_CPU0_P1_GND")
		)
		(pad "2" smd rect
			(at 0.2667 0 90)
			(size 0.3048 0.381)
			(layers "F.Cu" "F.Mask" "F.Paste")
			(net "GND")
		)
	)
	(footprint ""
		(layer "F.Cu")
		(at 204.7621 -405.036782 180)
		(property "Reference" "PC2185"
			(at 0 0 180)
			(layer "F.SilkS")
			(hide yes)
			(effects
				(font
					(size 1.27 1.27)
				)
			)
		)
		(property "Value" ""
			(at 0 0 180)
			(layer "F.Fab")
			(effects
				(font
					(size 1.27 1.27)
				)
			)
		)
		(duplicate_pad_numbers_are_jumpers no)
		(fp_line
			(start 0.7874 0.4064)
			(end -0.7874 0.4064)
			(stroke
				(width 0.1524)
				(type default)
			)
			(layer "F.SilkS")
		)
		(fp_line
			(start 0.7874 -0.4064)
			(end 0.7874 0.4064)
			(stroke
				(width 0.1524)
				(type default)
			)
			(layer "F.SilkS")
		)
		(fp_line
			(start -0.7874 0.4064)
			(end -0.7874 -0.4064)
			(stroke
				(width 0.1524)
				(type default)
			)
			(layer "F.SilkS")
		)
		(fp_line
			(start -0.7874 -0.4064)
			(end 0.7874 -0.4064)
			(stroke
				(width 0.1524)
				(type default)
			)
			(layer "F.SilkS")
		)
		(fp_line
			(start 0.67945 0.3048)
			(end 0.120396 0.3048)
			(stroke
				(width 0.1)
				(type default)
			)
			(layer "F.Fab")
		)
		(fp_line
			(start 0.67945 -0.3048)
			(end 0.67945 0.3048)
			(stroke
				(width 0.1)
				(type default)
			)
			(layer "F.Fab")
		)
		(fp_line
			(start 0.12065 -0.2794)
			(end 0.12065 -0.3048)
			(stroke
				(width 0.1)
				(type default)
			)
			(layer "F.Fab")
		)
		(fp_line
			(start 0.12065 -0.3048)
			(end 0.67945 -0.3048)
			(stroke
				(width 0.1)
				(type default)
			)
			(layer "F.Fab")
		)
		(fp_line
			(start 0.120396 0.3048)
			(end 0.120396 0.2794)
			(stroke
				(width 0.1)
				(type default)
			)
			(layer "F.Fab")
		)
		(fp_line
			(start 0.120396 0.2794)
			(end -0.12065 0.2794)
			(stroke
				(width 0.1)
				(type default)
			)
			(layer "F.Fab")
		)
		(fp_line
			(start -0.12065 0.3048)
			(end -0.67945 0.3048)
			(stroke
				(width 0.1)
				(type default)
			)
			(layer "F.Fab")
		)
		(fp_line
			(start -0.12065 0.2794)
			(end -0.12065 0.3048)
			(stroke
				(width 0.1)
				(type default)
			)
			(layer "F.Fab")
		)
		(fp_line
			(start -0.12065 -0.2794)
			(end 0.12065 -0.2794)
			(stroke
				(width 0.1)
				(type default)
			)
			(layer "F.Fab")
		)
		(fp_line
			(start -0.12065 -0.305054)
			(end -0.12065 -0.2794)
			(stroke
				(width 0.1)
				(type default)
			)
			(layer "F.Fab")
		)
		(fp_line
			(start -0.67945 0.3048)
			(end -0.67945 -0.305054)
			(stroke
				(width 0.1)
				(type default)
			)
			(layer "F.Fab")
		)
		(fp_line
			(start -0.67945 -0.305054)
			(end -0.12065 -0.305054)
			(stroke
				(width 0.1)
				(type default)
			)
			(layer "F.Fab")
		)
		(pad "1" smd circle
			(at -0.40005 0 180)
			(size 0 0)
			(layers "F.Cu" "F.Mask" "F.Paste")
			(net "HSC_SS")
		)
		(pad "2" smd circle
			(at 0.40005 0 180)
			(size 0 0)
			(layers "F.Cu" "F.Mask" "F.Paste")
			(net "AGND_HSC")
		)
	)
)
